# S9S_MB_2U (Grand Teton) — schematic netlist excerpt (pin names and nets, part order shuffled) for the footprints in the layout excerpt that follows; sources: Cadence DE-HDL packaged netlist, KiCad conversion of 03242023_DA0F0TMBIJ0_F0T_Motherboard_J_brd_V01_OCP.brd

R696  Q_RES  4.75K 1% CHIP  pkg 0402LF  page 182 : A = P3V3_AUX ; B = RST_PCH_RSTBTN_R_N
R362  Q_RES  0 5% CHIP  pkg 0402LF  page 278 : A = PWRGD_PVCCD_HV_CPU0 ; B = PWRGD_PVCCD_HV_CPU0_R

(kicad_pcb
	(version 20260206)
	(generator "pcbnew")
	(generator_version "10.0")
	(general
		(thickness 1.6)
		(legacy_teardrops no)
	)
	(paper "A4")
	(title_block
		(title "03242023_DA0F0TMBIJ0_F0T_Motherboard_J_brd_V01_OCP.brd")
		(comment 1 "Grand Teton / footprints 5549-5550 of 6105")
	)
	(layers
		(0 "F.Cu" signal "TOP")
		(4 "In1.Cu" signal "GND")
		(6 "In2.Cu" signal "IN1")
		(8 "In3.Cu" signal "GND1")
		(10 "In4.Cu" signal "IN2")
		(12 "In5.Cu" signal "GND2")
		(14 "In6.Cu" signal "IN3")
		(16 "In7.Cu" signal "GND3")
		(18 "In8.Cu" signal "VCC")
		(20 "In9.Cu" signal "VCC1")
		(22 "In10.Cu" signal "GND4")
		(24 "In11.Cu" signal "IN4")
		(26 "In12.Cu" signal "GND5")
		(28 "In13.Cu" signal "IN5")
		(30 "In14.Cu" signal "GND6")
		(32 "In15.Cu" signal "IN6")
		(34 "In16.Cu" signal "GND7")
		(2 "B.Cu" signal "BOTTOM")
		(9 "F.Adhes" user "F.Adhesive")
		(11 "B.Adhes" user "B.Adhesive")
		(13 "F.Paste" user "Package Geometry/Pastemask Top")
		(15 "B.Paste" user "Package Geometry/Pastemask Bottom")
		(5 "F.SilkS" user "Ref Des/Silkscreen Top")
		(7 "B.SilkS" user "Ref Des/Silkscreen Bottom")
		(1 "F.Mask" user "Board Geometry/Soldermask Top")
		(3 "B.Mask" user "Board Geometry/Soldermask Bottom")
		(17 "Dwgs.User" user "User.Drawings")
		(19 "Cmts.User" user "User.Comments")
		(21 "Eco1.User" user "User.Eco1")
		(23 "Eco2.User" user "User.Eco2")
		(25 "Edge.Cuts" user "Board Geometry/Outline")
		(27 "Margin" user)
		(31 "F.CrtYd" user "Package Geometry/Place Bound Top")
		(29 "B.CrtYd" user "Package Geometry/Place Bound Bottom")
		(35 "F.Fab" user "Ref Des/Assembly Top")
		(33 "B.Fab" user "Ref Des/Assembly Bottom")
	)
	(footprint ""
		(layer "B.Cu")
		(at 436.971694 -120.841008)
		(property "Reference" "R362"
			(at 0 0 0)
			(layer "B.SilkS")
			(hide yes)
			(effects
				(font
					(size 1.27 1.27)
				)
				(justify mirror)
			)
		)
		(property "Value" ""
			(at 0 0 0)
			(layer "B.Fab")
			(effects
				(font
					(size 1.27 1.27)
				)
				(justify mirror)
			)
		)
		(duplicate_pad_numbers_are_jumpers no)
		(fp_line
			(start -0.7874 -0.4064)
			(end -0.7874 0.4064)
			(stroke
				(width 0.1524)
				(type default)
			)
			(layer "B.SilkS")
		)
		(fp_line
			(start -0.7874 0.4064)
			(end 0.7874 0.4064)
			(stroke
				(width 0.1524)
				(type default)
			)
			(layer "B.SilkS")
		)
		(fp_line
			(start 0.7874 -0.4064)
			(end -0.7874 -0.4064)
			(stroke
				(width 0.1524)
				(type default)
			)
			(layer "B.SilkS")
		)
		(fp_line
			(start 0.7874 0.4064)
			(end 0.7874 -0.4064)
			(stroke
				(width 0.1524)
				(type default)
			)
			(layer "B.SilkS")
		)
		(fp_line
			(start -0.67945 -0.3048)
			(end -0.67945 0.3048)
			(stroke
				(width 0.1)
				(type default)
			)
			(layer "B.Fab")
		)
		(fp_line
			(start -0.67945 0.3048)
			(end -0.120396 0.3048)
			(stroke
				(width 0.1)
				(type default)
			)
			(layer "B.Fab")
		)
		(fp_line
			(start -0.12065 -0.3048)
			(end -0.67945 -0.3048)
			(stroke
				(width 0.1)
				(type default)
			)
			(layer "B.Fab")
		)
		(fp_line
			(start -0.12065 -0.2794)
			(end -0.12065 -0.3048)
			(stroke
				(width 0.1)
				(type default)
			)
			(layer "B.Fab")
		)
		(fp_line
			(start -0.120396 0.2794)
			(end 0.12065 0.2794)
			(stroke
				(width 0.1)
				(type default)
			)
			(layer "B.Fab")
		)
		(fp_line
			(start -0.120396 0.3048)
			(end -0.120396 0.2794)
			(stroke
				(width 0.1)
				(type default)
			)
			(layer "B.Fab")
		)
		(fp_line
			(start 0.12065 -0.305054)
			(end 0.12065 -0.2794)
			(stroke
				(width 0.1)
				(type default)
			)
			(layer "B.Fab")
		)
		(fp_line
			(start 0.12065 -0.2794)
			(end -0.12065 -0.2794)
			(stroke
				(width 0.1)
				(type default)
			)
			(layer "B.Fab")
		)
		(fp_line
			(start 0.12065 0.2794)
			(end 0.12065 0.3048)
			(stroke
				(width 0.1)
				(type default)
			)
			(layer "B.Fab")
		)
		(fp_line
			(start 0.12065 0.3048)
			(end 0.67945 0.3048)
			(stroke
				(width 0.1)
				(type default)
			)
			(layer "B.Fab")
		)
		(fp_line
			(start 0.67945 -0.305054)
			(end 0.12065 -0.305054)
			(stroke
				(width 0.1)
				(type default)
			)
			(layer "B.Fab")
		)
		(fp_line
			(start 0.67945 0.3048)
			(end 0.67945 -0.305054)
			(stroke
				(width 0.1)
				(type default)
			)
			(layer "B.Fab")
		)
		(pad "1" smd circle
			(at 0.40005 0 180)
			(size 0 0)
			(layers "B.Cu" "B.Mask" "B.Paste")
			(net "PWRGD_PVCCD_HV_CPU0")
		)
		(pad "2" smd circle
			(at -0.40005 0 180)
			(size 0 0)
			(layers "B.Cu" "B.Mask" "B.Paste")
			(net "PWRGD_PVCCD_HV_CPU0_R")
		)
	)
	(footprint ""
		(layer "B.Cu")
		(at 319.425066 -40.970454 -135)
		(property "Reference" "R696"
			(at 0 0 45)
			(layer "B.SilkS")
			(hide yes)
			(effects
				(font
					(size 1.27 1.27)
				)
				(justify mirror)
			)
		)
		(property "Value" ""
			(at 0 0 45)
			(layer "B.Fab")
			(effects
				(font
					(size 1.27 1.27)
				)
				(justify mirror)
			)
		)
		(duplicate_pad_numbers_are_jumpers no)
		(fp_line
			(start 0.787389 0.406267)
			(end 0.787389 -0.406267)
			(stroke
				(width 0.1524)
				(type default)
			)
			(layer "B.SilkS")
		)
		(fp_line
			(start 0.787389 -0.406267)
			(end -0.787389 -0.406267)
			(stroke
				(width 0.1524)
				(type default)
			)
			(layer "B.SilkS")
		)
		(fp_line
			(start -0.787389 0.406267)
			(end 0.787389 0.406267)
			(stroke
				(width 0.1524)
				(type default)
			)
			(layer "B.SilkS")
		)
		(fp_line
			(start -0.787389 -0.406267)
			(end -0.787389 0.406267)
			(stroke
				(width 0.1524)
				(type default)
			)
			(layer "B.SilkS")
		)
		(fp_line
			(start 0.679446 0.30479)
			(end 0.679446 -0.305149)
			(stroke
				(width 0.1)
				(type default)
			)
			(layer "B.Fab")
		)
		(fp_line
			(start 0.120515 0.30479)
			(end 0.679446 0.30479)
			(stroke
				(width 0.1)
				(type default)
			)
			(layer "B.Fab")
		)
		(fp_line
			(start 0.120695 0.279466)
			(end 0.120515 0.30479)
			(stroke
				(width 0.1)
				(type default)
			)
			(layer "B.Fab")
		)
		(fp_line
			(start 0.679446 -0.305149)
			(end 0.120695 -0.304969)
			(stroke
				(width 0.1)
				(type default)
			)
			(layer "B.Fab")
		)
		(fp_line
			(start -0.120515 0.30479)
			(end -0.120335 0.279466)
			(stroke
				(width 0.1)
				(type default)
			)
			(layer "B.Fab")
		)
		(fp_line
			(start -0.120335 0.279466)
			(end 0.120695 0.279466)
			(stroke
				(width 0.1)
				(type default)
			)
			(layer "B.Fab")
		)
		(fp_line
			(start 0.120695 -0.279466)
			(end -0.120695 -0.279466)
			(stroke
				(width 0.1)
				(type default)
			)
			(layer "B.Fab")
		)
		(fp_line
			(start 0.120695 -0.304969)
			(end 0.120695 -0.279466)
			(stroke
				(width 0.1)
				(type default)
			)
			(layer "B.Fab")
		)
		(fp_line
			(start -0.679446 0.30479)
			(end -0.120515 0.30479)
			(stroke
				(width 0.1)
				(type default)
			)
			(layer "B.Fab")
		)
		(fp_line
			(start -0.120695 -0.279466)
			(end -0.120515 -0.30479)
			(stroke
				(width 0.1)
				(type default)
			)
			(layer "B.Fab")
		)
		(fp_line
			(start -0.120515 -0.30479)
			(end -0.679446 -0.30479)
			(stroke
				(width 0.1)
				(type default)
			)
			(layer "B.Fab")
		)
		(fp_line
			(start -0.679446 -0.30479)
			(end -0.679446 0.30479)
			(stroke
				(width 0.1)
				(type default)
			)
			(layer "B.Fab")
		)
		(pad "1" smd circle
			(at 0.40005 0 45)
			(size 0 0)
			(layers "B.Cu" "B.Mask" "B.Paste")
			(net "P3V3_AUX")
		)
		(pad "2" smd circle
			(at -0.40005 0 45)
			(size 0 0)
			(layers "B.Cu" "B.Mask" "B.Paste")
			(net "RST_PCH_RSTBTN_R_N")
		)
	)
)
